(kicad_pcb
	(version 20260206)
	(generator "pcbnew")
	(generator_version "10.0")
	(general
		(thickness 1.6)
		(legacy_teardrops no)
	)
	(paper "A4")
	(title_block
		(title "peb — Lightning_PEB_BRD.brd")
		(comment 1 "Lightning (Wiwynn / Facebook NVMe JBOF) / footprints 2239-2246 of 2563")
	)
	(layers
		(0 "F.Cu" signal "TOP")
		(4 "In1.Cu" signal "L2GND")
		(6 "In2.Cu" signal "L3")
		(8 "In3.Cu" signal "L4VCC")
		(10 "In4.Cu" signal "L5VCC")
		(12 "In5.Cu" signal "L6")
		(14 "In6.Cu" signal "L7GND")
		(2 "B.Cu" signal "BOTTOM")
		(9 "F.Adhes" user "F.Adhesive")
		(11 "B.Adhes" user "B.Adhesive")
		(13 "F.Paste" user "Package Geometry/Pastemask Top")
		(15 "B.Paste" user "Package Geometry/Pastemask Bottom")
		(5 "F.SilkS" user "Ref Des/Silkscreen Top")
		(7 "B.SilkS" user "Ref Des/Silkscreen Bottom")
		(1 "F.Mask" user "Board Geometry/Soldermask Top")
		(3 "B.Mask" user "Board Geometry/Soldermask Bottom")
		(17 "Dwgs.User" user "User.Drawings")
		(19 "Cmts.User" user "User.Comments")
		(21 "Eco1.User" user "User.Eco1")
		(23 "Eco2.User" user "User.Eco2")
		(25 "Edge.Cuts" user "Board Geometry/Outline")
		(27 "Margin" user)
		(31 "F.CrtYd" user "Package Geometry/Place Bound Top")
		(29 "B.CrtYd" user "Package Geometry/Place Bound Bottom")
		(35 "F.Fab" user "Ref Des/Assembly Top")
		(33 "B.Fab" user "Ref Des/Assembly Bottom")
	)
	(footprint ""
		(layer "B.Cu")
		(at 181.64302 -13.9446)
		(property "Reference" "R273"
			(at 0 0 0)
			(layer "B.SilkS")
			(hide yes)
			(effects
				(font
					(size 1.27 1.27)
				)
				(justify mirror)
			)
		)
		(property "Value" "0R2J-2-GP"
			(at -0.064008 -3.993896 0)
			(unlocked yes)
			(layer "B.Fab")
			(hide yes)
			(effects
				(font
					(size 1.016 1.016)
					(thickness 0.1524)
				)
				(justify mirror)
			)
		)
		(property "Device Type" "R402H16"
			(at -0.064008 -5.517896 0)
			(unlocked yes)
			(layer "B.Fab")
			(hide yes)
			(effects
				(font
					(size 1.016 1.016)
					(thickness 0.1524)
				)
				(justify mirror)
			)
		)
		(duplicate_pad_numbers_are_jumpers no)
		(fp_line
			(start -0.508 -0.9398)
			(end 0.508 -0.9398)
			(stroke
				(width 0.1524)
				(type default)
			)
			(layer "B.SilkS")
		)
		(fp_line
			(start 0.508 -0.9398)
			(end 0.508 0.9398)
			(stroke
				(width 0.1524)
				(type default)
			)
			(layer "B.SilkS")
		)
		(fp_rect
			(start 0.508 0.9398)
			(end -0.508 -0.9398)
			(stroke
				(width 0)
				(type default)
			)
			(fill no)
			(layer "B.CrtYd")
		)
		(fp_rect
			(start 0.508 0.9398)
			(end -0.508 -0.9398)
			(stroke
				(width 0)
				(type default)
			)
			(fill no)
			(layer "B.Fab")
		)
		(pad "1" smd custom
			(at 0 -0.4445 180)
			(size 0.1397 0.1397)
			(layers "B.Cu" "B.Mask" "B.Paste")
			(net "MINISAS_CN15_C_I2C_INT#")
			(options
				(clearance outline)
				(anchor circle)
			)
			(primitives
				(gr_poly
					(pts
						(arc
							(start -0.1778 0.2794)
							(mid -0.249642 0.249642)
							(end -0.2794 0.1778)
						)
						(arc
							(start -0.2794 -0.1778)
							(mid -0.249642 -0.249642)
							(end -0.1778 -0.2794)
						)
						(arc
							(start 0.1778 -0.2794)
							(mid 0.249642 -0.249642)
							(end 0.2794 -0.1778)
						)
						(arc
							(start 0.2794 0.1778)
							(mid 0.249642 0.249642)
							(end 0.1778 0.2794)
						)
					)
					(width 0)
					(fill yes)
				)
			)
		)
		(pad "2" smd custom
			(at 0 0.4445 180)
			(size 0.1397 0.1397)
			(layers "B.Cu" "B.Mask" "B.Paste")
			(net "PCIE_REFCLK_H3_N_R")
			(options
				(clearance outline)
				(anchor circle)
			)
			(primitives
				(gr_poly
					(pts
						(arc
							(start -0.1778 0.2794)
							(mid -0.249642 0.249642)
							(end -0.2794 0.1778)
						)
						(arc
							(start -0.2794 -0.1778)
							(mid -0.249642 -0.249642)
							(end -0.1778 -0.2794)
						)
						(arc
							(start 0.1778 -0.2794)
							(mid 0.249642 -0.249642)
							(end 0.2794 -0.1778)
						)
						(arc
							(start 0.2794 0.1778)
							(mid 0.249642 0.249642)
							(end 0.1778 0.2794)
						)
					)
					(width 0)
					(fill yes)
				)
			)
		)
	)
	(footprint ""
		(layer "B.Cu")
		(at 182.648098 -51.293268 90)
		(property "Reference" "R43"
			(at 0 0 90)
			(layer "B.SilkS")
			(hide yes)
			(effects
				(font
					(size 1.27 1.27)
				)
				(justify mirror)
			)
		)
		(property "Value" "1KR3F-GP"
			(at 0.0254 -2.5146 90)
			(unlocked yes)
			(layer "B.Fab")
			(hide yes)
			(effects
				(font
					(size 1.016 1.016)
					(thickness 0.1524)
				)
				(justify mirror)
			)
		)
		(property "Device Type" "R603H22"
			(at 0.0254 -4.0386 90)
			(unlocked yes)
			(layer "B.Fab")
			(hide yes)
			(effects
				(font
					(size 1.016 1.016)
					(thickness 0.1524)
				)
				(justify mirror)
			)
		)
		(duplicate_pad_numbers_are_jumpers no)
		(fp_line
			(start 0.4826 0)
			(end 0.2032 0)
			(stroke
				(width 0.2032)
				(type default)
			)
			(layer "B.SilkS")
		)
		(fp_line
			(start -0.2032 0)
			(end -0.4826 0)
			(stroke
				(width 0.2032)
				(type default)
			)
			(layer "B.SilkS")
		)
		(fp_rect
			(start 0.5842 1.3335)
			(end -0.5842 -1.3335)
			(stroke
				(width 0)
				(type default)
			)
			(fill no)
			(layer "B.CrtYd")
		)
		(fp_rect
			(start 0.5842 1.3335)
			(end -0.5842 -1.3335)
			(stroke
				(width 0)
				(type default)
			)
			(fill no)
			(layer "B.Fab")
		)
		(pad "1" smd custom
			(at 0 -0.762 270)
			(size 0.2159 0.2159)
			(layers "B.Cu" "B.Mask" "B.Paste")
			(net "DUT_AVD_PCIE")
			(options
				(clearance outline)
				(anchor circle)
			)
			(primitives
				(gr_poly
					(pts
						(arc
							(start -0.3302 0.4318)
							(mid -0.402042 0.402042)
							(end -0.4318 0.3302)
						)
						(arc
							(start -0.4318 -0.3302)
							(mid -0.402042 -0.402042)
							(end -0.3302 -0.4318)
						)
						(arc
							(start 0.3302 -0.4318)
							(mid 0.402042 -0.402042)
							(end 0.4318 -0.3302)
						)
						(arc
							(start 0.4318 0.3302)
							(mid 0.402042 0.402042)
							(end 0.3302 0.4318)
						)
					)
					(width 0)
					(fill yes)
				)
			)
		)
		(pad "2" smd custom
			(at 0 0.762 270)
			(size 0.2159 0.2159)
			(layers "B.Cu" "B.Mask" "B.Paste")
			(net "DUT_AVD_PCIE_Q")
			(options
				(clearance outline)
				(anchor circle)
			)
			(primitives
				(gr_poly
					(pts
						(arc
							(start -0.3302 0.4318)
							(mid -0.402042 0.402042)
							(end -0.4318 0.3302)
						)
						(arc
							(start -0.4318 -0.3302)
							(mid -0.402042 -0.402042)
							(end -0.3302 -0.4318)
						)
						(arc
							(start 0.3302 -0.4318)
							(mid 0.402042 -0.402042)
							(end 0.4318 -0.3302)
						)
						(arc
							(start 0.4318 0.3302)
							(mid 0.402042 0.402042)
							(end 0.3302 0.4318)
						)
					)
					(width 0)
					(fill yes)
				)
			)
		)
	)
	(footprint ""
		(layer "B.Cu")
		(at 340.5886 -181.8386)
		(property "Reference" "R3244"
			(at 0 0 0)
			(layer "B.SilkS")
			(hide yes)
			(effects
				(font
					(size 1.27 1.27)
				)
				(justify mirror)
			)
		)
		(property "Value" "0R2J-2-GP"
			(at -0.064008 -3.993896 0)
			(unlocked yes)
			(layer "B.Fab")
			(hide yes)
			(effects
				(font
					(size 1.016 1.016)
					(thickness 0.1524)
				)
				(justify mirror)
			)
		)
		(property "Device Type" "R402H16"
			(at -0.064008 -5.517896 0)
			(unlocked yes)
			(layer "B.Fab")
			(hide yes)
			(effects
				(font
					(size 1.016 1.016)
					(thickness 0.1524)
				)
				(justify mirror)
			)
		)
		(duplicate_pad_numbers_are_jumpers no)
		(fp_line
			(start -0.508 -0.9398)
			(end 0.508 -0.9398)
			(stroke
				(width 0.1524)
				(type default)
			)
			(layer "B.SilkS")
		)
		(fp_line
			(start 0.508 -0.9398)
			(end 0.508 0.9398)
			(stroke
				(width 0.1524)
				(type default)
			)
			(layer "B.SilkS")
		)
		(fp_rect
			(start 0.508 0.9398)
			(end -0.508 -0.9398)
			(stroke
				(width 0)
				(type default)
			)
			(fill no)
			(layer "B.CrtYd")
		)
		(fp_rect
			(start 0.508 0.9398)
			(end -0.508 -0.9398)
			(stroke
				(width 0)
				(type default)
			)
			(fill no)
			(layer "B.Fab")
		)
		(pad "1" smd custom
			(at 0 -0.4445 180)
			(size 0.1397 0.1397)
			(layers "B.Cu" "B.Mask" "B.Paste")
			(net "BMC_SSD_RST#14")
			(options
				(clearance outline)
				(anchor circle)
			)
			(primitives
				(gr_poly
					(pts
						(arc
							(start -0.1778 0.2794)
							(mid -0.249642 0.249642)
							(end -0.2794 0.1778)
						)
						(arc
							(start -0.2794 -0.1778)
							(mid -0.249642 -0.249642)
							(end -0.1778 -0.2794)
						)
						(arc
							(start 0.1778 -0.2794)
							(mid 0.249642 -0.249642)
							(end 0.2794 -0.1778)
						)
						(arc
							(start 0.2794 0.1778)
							(mid 0.249642 0.249642)
							(end 0.1778 0.2794)
						)
					)
					(width 0)
					(fill yes)
				)
			)
		)
		(pad "2" smd custom
			(at 0 0.4445 180)
			(size 0.1397 0.1397)
			(layers "B.Cu" "B.Mask" "B.Paste")
			(net "BMC_SSD_RST#0_A14")
			(options
				(clearance outline)
				(anchor circle)
			)
			(primitives
				(gr_poly
					(pts
						(arc
							(start -0.1778 0.2794)
							(mid -0.249642 0.249642)
							(end -0.2794 0.1778)
						)
						(arc
							(start -0.2794 -0.1778)
							(mid -0.249642 -0.249642)
							(end -0.1778 -0.2794)
						)
						(arc
							(start 0.1778 -0.2794)
							(mid 0.249642 -0.249642)
							(end 0.2794 -0.1778)
						)
						(arc
							(start 0.2794 0.1778)
							(mid 0.249642 0.249642)
							(end 0.1778 0.2794)
						)
					)
					(width 0)
					(fill yes)
				)
			)
		)
	)
	(footprint ""
		(layer "B.Cu")
		(at 66.548 -149.479 -90)
		(property "Reference" "R208"
			(at 0 0 90)
			(layer "B.SilkS")
			(hide yes)
			(effects
				(font
					(size 1.27 1.27)
				)
				(justify mirror)
			)
		)
		(property "Value" "0R2J-2-GP"
			(at -0.064008 -3.993896 270)
			(unlocked yes)
			(layer "B.Fab")
			(hide yes)
			(effects
				(font
					(size 1.016 1.016)
					(thickness 0.1524)
				)
				(justify mirror)
			)
		)
		(property "Device Type" "R402H16"
			(at -0.064008 -5.517896 270)
			(unlocked yes)
			(layer "B.Fab")
			(hide yes)
			(effects
				(font
					(size 1.016 1.016)
					(thickness 0.1524)
				)
				(justify mirror)
			)
		)
		(duplicate_pad_numbers_are_jumpers no)
		(fp_line
			(start -0.508 -0.9398)
			(end 0.508 -0.9398)
			(stroke
				(width 0.1524)
				(type default)
			)
			(layer "B.SilkS")
		)
		(fp_line
			(start 0.508 -0.9398)
			(end 0.508 0.9398)
			(stroke
				(width 0.1524)
				(type default)
			)
			(layer "B.SilkS")
		)
		(fp_rect
			(start 0.508 0.9398)
			(end -0.508 -0.9398)
			(stroke
				(width 0)
				(type default)
			)
			(fill no)
			(layer "B.CrtYd")
		)
		(fp_rect
			(start 0.508 0.9398)
			(end -0.508 -0.9398)
			(stroke
				(width 0)
				(type default)
			)
			(fill no)
			(layer "B.Fab")
		)
		(pad "1" smd custom
			(at 0 -0.4445 90)
			(size 0.1397 0.1397)
			(layers "B.Cu" "B.Mask" "B.Paste")
			(net "EEPROM_SCL")
			(options
				(clearance outline)
				(anchor circle)
			)
			(primitives
				(gr_poly
					(pts
						(arc
							(start -0.1778 0.2794)
							(mid -0.249642 0.249642)
							(end -0.2794 0.1778)
						)
						(arc
							(start -0.2794 -0.1778)
							(mid -0.249642 -0.249642)
							(end -0.1778 -0.2794)
						)
						(arc
							(start 0.1778 -0.2794)
							(mid 0.249642 -0.249642)
							(end 0.2794 -0.1778)
						)
						(arc
							(start 0.2794 0.1778)
							(mid 0.249642 0.249642)
							(end 0.1778 0.2794)
						)
					)
					(width 0)
					(fill yes)
				)
			)
		)
		(pad "2" smd custom
			(at 0 0.4445 90)
			(size 0.1397 0.1397)
			(layers "B.Cu" "B.Mask" "B.Paste")
			(net "BMC_I2C5_D_PEB_SCL")
			(options
				(clearance outline)
				(anchor circle)
			)
			(primitives
				(gr_poly
					(pts
						(arc
							(start -0.1778 0.2794)
							(mid -0.249642 0.249642)
							(end -0.2794 0.1778)
						)
						(arc
							(start -0.2794 -0.1778)
							(mid -0.249642 -0.249642)
							(end -0.1778 -0.2794)
						)
						(arc
							(start 0.1778 -0.2794)
							(mid 0.249642 -0.249642)
							(end 0.2794 -0.1778)
						)
						(arc
							(start 0.2794 0.1778)
							(mid 0.249642 0.249642)
							(end 0.1778 0.2794)
						)
					)
					(width 0)
					(fill yes)
				)
			)
		)
	)
	(footprint ""
		(layer "B.Cu")
		(at 23.796498 -126.005336 90)
		(property "Reference" "R356"
			(at 0 0 90)
			(layer "B.SilkS")
			(hide yes)
			(effects
				(font
					(size 1.27 1.27)
				)
				(justify mirror)
			)
		)
		(property "Value" "3K3R2F-2-GP"
			(at -0.064008 -3.993896 90)
			(unlocked yes)
			(layer "B.Fab")
			(hide yes)
			(effects
				(font
					(size 1.016 1.016)
					(thickness 0.1524)
				)
				(justify mirror)
			)
		)
		(property "Device Type" "R402H16"
			(at -0.064008 -5.517896 90)
			(unlocked yes)
			(layer "B.Fab")
			(hide yes)
			(effects
				(font
					(size 1.016 1.016)
					(thickness 0.1524)
				)
				(justify mirror)
			)
		)
		(duplicate_pad_numbers_are_jumpers no)
		(fp_line
			(start 0.508 -0.9398)
			(end 0.508 0.9398)
			(stroke
				(width 0.1524)
				(type default)
			)
			(layer "B.SilkS")
		)
		(fp_line
			(start -0.508 -0.9398)
			(end 0.508 -0.9398)
			(stroke
				(width 0.1524)
				(type default)
			)
			(layer "B.SilkS")
		)
		(fp_rect
			(start 0.508 0.9398)
			(end -0.508 -0.9398)
			(stroke
				(width 0)
				(type default)
			)
			(fill no)
			(layer "B.CrtYd")
		)
		(fp_rect
			(start 0.508 0.9398)
			(end -0.508 -0.9398)
			(stroke
				(width 0)
				(type default)
			)
			(fill no)
			(layer "B.Fab")
		)
		(pad "1" smd custom
			(at 0 -0.4445 270)
			(size 0.1397 0.1397)
			(layers "B.Cu" "B.Mask" "B.Paste")
			(net "P3V3_STBY")
			(options
				(clearance outline)
				(anchor circle)
			)
			(primitives
				(gr_poly
					(pts
						(arc
							(start -0.1778 0.2794)
							(mid -0.249642 0.249642)
							(end -0.2794 0.1778)
						)
						(arc
							(start -0.2794 -0.1778)
							(mid -0.249642 -0.249642)
							(end -0.1778 -0.2794)
						)
						(arc
							(start 0.1778 -0.2794)
							(mid 0.249642 -0.249642)
							(end 0.2794 -0.1778)
						)
						(arc
							(start 0.2794 0.1778)
							(mid 0.249642 0.249642)
							(end 0.1778 0.2794)
						)
					)
					(width 0)
					(fill yes)
				)
			)
		)
		(pad "2" smd custom
			(at 0 0.4445 270)
			(size 0.1397 0.1397)
			(layers "B.Cu" "B.Mask" "B.Paste")
			(net "ROMA12")
			(options
				(clearance outline)
				(anchor circle)
			)
			(primitives
				(gr_poly
					(pts
						(arc
							(start -0.1778 0.2794)
							(mid -0.249642 0.249642)
							(end -0.2794 0.1778)
						)
						(arc
							(start -0.2794 -0.1778)
							(mid -0.249642 -0.249642)
							(end -0.1778 -0.2794)
						)
						(arc
							(start 0.1778 -0.2794)
							(mid 0.249642 -0.249642)
							(end 0.2794 -0.1778)
						)
						(arc
							(start 0.2794 0.1778)
							(mid 0.249642 0.249642)
							(end 0.1778 0.2794)
						)
					)
					(width 0)
					(fill yes)
				)
			)
		)
	)
	(footprint ""
		(layer "B.Cu")
		(at 310.007 -56.261 180)
		(property "Reference" "PG61"
			(at 0 0 0)
			(layer "B.SilkS")
			(hide yes)
			(effects
				(font
					(size 1.27 1.27)
				)
				(justify mirror)
			)
		)
		(property "Value" "GAP-CLOSE-PWR-3-GP"
			(at -0.0254 -6.5786 180)
			(unlocked yes)
			(layer "B.Fab")
			(hide yes)
			(effects
				(font
					(size 1.016 1.016)
					(thickness 0.1524)
				)
				(justify mirror)
			)
		)
		(property "Device Type" "GAP-CLOSE-PWR-3"
			(at -0.0254 -8.255 180)
			(unlocked yes)
			(layer "B.Fab")
			(hide yes)
			(effects
				(font
					(size 1.016 1.016)
					(thickness 0.1524)
				)
				(justify mirror)
			)
		)
		(duplicate_pad_numbers_are_jumpers no)
		(fp_rect
			(start 0.7112 0.4572)
			(end -0.7112 -0.4572)
			(stroke
				(width 0)
				(type default)
			)
			(fill no)
			(layer "B.CrtYd")
		)
		(fp_poly
			(pts
				(xy 0.7112 -0.4572) (xy -0.7112 -0.4572) (xy -0.7112 0.4572) (xy 0.7112 0.4572)
			)
			(stroke
				(width 0)
				(type default)
			)
			(fill no)
			(layer "B.Fab")
		)
		(pad "1" smd rect
			(at 0.3048 0)
			(size 0.6604 0.762)
			(layers "B.Cu" "B.Mask" "B.Paste")
			(net "DUT_VDD")
		)
		(pad "2" smd rect
			(at -0.3048 0)
			(size 0.6604 0.762)
			(layers "B.Cu" "B.Mask" "B.Paste")
			(net "P0V9_E")
		)
	)
	(footprint ""
		(layer "B.Cu")
		(at 158.508192 -33.589976)
		(property "Reference" "R2924"
			(at 0 0 0)
			(layer "B.SilkS")
			(hide yes)
			(effects
				(font
					(size 1.27 1.27)
				)
				(justify mirror)
			)
		)
		(property "Value" "0R2J-2-GP"
			(at -0.064008 -3.993896 0)
			(unlocked yes)
			(layer "B.Fab")
			(hide yes)
			(effects
				(font
					(size 1.016 1.016)
					(thickness 0.1524)
				)
				(justify mirror)
			)
		)
		(property "Device Type" "R402H16"
			(at -0.064008 -5.517896 0)
			(unlocked yes)
			(layer "B.Fab")
			(hide yes)
			(effects
				(font
					(size 1.016 1.016)
					(thickness 0.1524)
				)
				(justify mirror)
			)
		)
		(duplicate_pad_numbers_are_jumpers no)
		(fp_line
			(start -0.508 -0.9398)
			(end 0.508 -0.9398)
			(stroke
				(width 0.1524)
				(type default)
			)
			(layer "B.SilkS")
		)
		(fp_line
			(start 0.508 -0.9398)
			(end 0.508 0.9398)
			(stroke
				(width 0.1524)
				(type default)
			)
			(layer "B.SilkS")
		)
		(fp_rect
			(start 0.508 0.9398)
			(end -0.508 -0.9398)
			(stroke
				(width 0)
				(type default)
			)
			(fill no)
			(layer "B.CrtYd")
		)
		(fp_rect
			(start 0.508 0.9398)
			(end -0.508 -0.9398)
			(stroke
				(width 0)
				(type default)
			)
			(fill no)
			(layer "B.Fab")
		)
		(pad "1" smd custom
			(at 0 -0.4445 180)
			(size 0.1397 0.1397)
			(layers "B.Cu" "B.Mask" "B.Paste")
			(net "CBL_PRSNT_N_3")
			(options
				(clearance outline)
				(anchor circle)
			)
			(primitives
				(gr_poly
					(pts
						(arc
							(start -0.1778 0.2794)
							(mid -0.249642 0.249642)
							(end -0.2794 0.1778)
						)
						(arc
							(start -0.2794 -0.1778)
							(mid -0.249642 -0.249642)
							(end -0.1778 -0.2794)
						)
						(arc
							(start 0.1778 -0.2794)
							(mid 0.249642 -0.249642)
							(end 0.2794 -0.1778)
						)
						(arc
							(start 0.2794 0.1778)
							(mid 0.249642 0.249642)
							(end 0.1778 0.2794)
						)
					)
					(width 0)
					(fill yes)
				)
			)
		)
		(pad "2" smd custom
			(at 0 0.4445 180)
			(size 0.1397 0.1397)
			(layers "B.Cu" "B.Mask" "B.Paste")
			(net "8644_CBL_PRSNT_R_3")
			(options
				(clearance outline)
				(anchor circle)
			)
			(primitives
				(gr_poly
					(pts
						(arc
							(start -0.1778 0.2794)
							(mid -0.249642 0.249642)
							(end -0.2794 0.1778)
						)
						(arc
							(start -0.2794 -0.1778)
							(mid -0.249642 -0.249642)
							(end -0.1778 -0.2794)
						)
						(arc
							(start 0.1778 -0.2794)
							(mid 0.249642 -0.249642)
							(end 0.2794 -0.1778)
						)
						(arc
							(start 0.2794 0.1778)
							(mid 0.249642 0.249642)
							(end 0.1778 0.2794)
						)
					)
					(width 0)
					(fill yes)
				)
			)
		)
	)
	(footprint ""
		(layer "B.Cu")
		(at 235.331 -71.882 -90)
		(property "Reference" "C496"
			(at 0 0 90)
			(layer "B.SilkS")
			(hide yes)
			(effects
				(font
					(size 1.27 1.27)
				)
				(justify mirror)
			)
		)
		(property "Value" "SC4D7U16V5KX-1-GP"
			(at 0.0762 -6.1214 270)
			(unlocked yes)
			(layer "B.Fab")
			(hide yes)
			(effects
				(font
					(size 1.016 1.016)
					(thickness 0.1524)
				)
				(justify mirror)
			)
		)
		(property "Device Type" "C805H56"
			(at 0.0762 -8.1534 270)
			(unlocked yes)
			(layer "B.Fab")
			(hide yes)
			(effects
				(font
					(size 1.016 1.016)
					(thickness 0.1524)
				)
				(justify mirror)
			)
		)
		(duplicate_pad_numbers_are_jumpers no)
		(fp_line
			(start -0.635 0)
			(end 0.635 0)
			(stroke
				(width 0.508)
				(type default)
			)
			(layer "B.SilkS")
		)
		(fp_rect
			(start 0.9652 1.778)
			(end -0.9652 -1.778)
			(stroke
				(width 0)
				(type default)
			)
			(fill no)
			(layer "B.CrtYd")
		)
		(fp_poly
			(pts
				(xy 0.9652 -1.778) (xy -0.9652 -1.778) (xy -0.9652 1.778) (xy 0.9652 1.778)
			)
			(stroke
				(width 0)
				(type default)
			)
			(fill no)
			(layer "B.Fab")
		)
		(pad "1" smd rect
			(at 0 -0.9652 90)
			(size 1.397 1.143)
			(layers "B.Cu" "B.Mask" "B.Paste")
			(net "DUT_AVD_TX")
		)
		(pad "2" smd rect
			(at 0 0.9652 90)
			(size 1.397 1.143)
			(layers "B.Cu" "B.Mask" "B.Paste")
			(net "GND")
		)
	)
)
